(kicad_pcb
	(version 20260206)
	(generator "pcbnew")
	(generator_version "10.0")
	(general
		(thickness 1.6)
		(legacy_teardrops no)
	)
	(paper "A4")
	(title_block
		(title "panther-plus-userver — 13130-1b_20150205.brd")
		(comment 1 "Honey Badger (Wiwynn) / footprints 655-662 of 1509")
	)
	(layers
		(0 "F.Cu" signal "TOP")
		(4 "In1.Cu" signal "L2")
		(6 "In2.Cu" signal "L3")
		(8 "In3.Cu" signal "L4")
		(10 "In4.Cu" signal "L5")
		(12 "In5.Cu" signal "L6")
		(14 "In6.Cu" signal "L7")
		(16 "In7.Cu" signal "L8")
		(18 "In8.Cu" signal "L9")
		(20 "In9.Cu" signal "L10")
		(22 "In10.Cu" signal "L11")
		(2 "B.Cu" signal "BOTTOM")
		(9 "F.Adhes" user "F.Adhesive")
		(11 "B.Adhes" user "B.Adhesive")
		(13 "F.Paste" user "Package Geometry/Pastemask Top")
		(15 "B.Paste" user "Package Geometry/Pastemask Bottom")
		(5 "F.SilkS" user "Ref Des/Silkscreen Top")
		(7 "B.SilkS" user "Ref Des/Silkscreen Bottom")
		(1 "F.Mask" user "Board Geometry/Soldermask Top")
		(3 "B.Mask" user "Board Geometry/Soldermask Bottom")
		(17 "Dwgs.User" user "User.Drawings")
		(19 "Cmts.User" user "User.Comments")
		(21 "Eco1.User" user "User.Eco1")
		(23 "Eco2.User" user "User.Eco2")
		(25 "Edge.Cuts" user "Board Geometry/Outline")
		(27 "Margin" user)
		(31 "F.CrtYd" user "Package Geometry/Place Bound Top")
		(29 "B.CrtYd" user "Package Geometry/Place Bound Bottom")
		(35 "F.Fab" user "Ref Des/Assembly Top")
		(33 "B.Fab" user "Ref Des/Assembly Bottom")
	)
	(footprint ""
		(layer "F.Cu")
		(at 73.279 -41.656 -90)
		(property "Reference" "R306"
			(at 0 0 270)
			(layer "F.SilkS")
			(hide yes)
			(effects
				(font
					(size 1.27 1.27)
				)
			)
		)
		(property "Value" "4K7R2F-GP"
			(at 0.064008 -3.993896 270)
			(unlocked yes)
			(layer "F.Fab")
			(hide yes)
			(effects
				(font
					(size 1.016 1.016)
					(thickness 0.1524)
				)
			)
		)
		(property "Device Type" "R402H16"
			(at 0.064008 -5.517896 270)
			(unlocked yes)
			(layer "F.Fab")
			(hide yes)
			(effects
				(font
					(size 1.016 1.016)
					(thickness 0.1524)
				)
			)
		)
		(duplicate_pad_numbers_are_jumpers no)
		(fp_rect
			(start -0.381 0.8382)
			(end 0.381 -0.8382)
			(stroke
				(width 0)
				(type default)
			)
			(fill no)
			(layer "F.CrtYd")
		)
		(fp_rect
			(start -0.381 0.8382)
			(end 0.381 -0.8382)
			(stroke
				(width 0)
				(type default)
			)
			(fill no)
			(layer "F.Fab")
		)
		(pad "1" smd custom
			(at 0 -0.4318 270)
			(size 0.127 0.127)
			(layers "F.Cu" "F.Mask" "F.Paste")
			(net "P3V3")
			(options
				(clearance outline)
				(anchor circle)
			)
			(primitives
				(gr_poly
					(pts
						(arc
							(start -0.2032 -0.2794)
							(mid -0.239121 -0.264521)
							(end -0.254 -0.2286)
						)
						(arc
							(start -0.254 0.2286)
							(mid -0.239121 0.264521)
							(end -0.2032 0.2794)
						)
						(arc
							(start 0.2032 0.2794)
							(mid 0.239121 0.264521)
							(end 0.254 0.2286)
						)
						(arc
							(start 0.254 -0.2286)
							(mid 0.239121 -0.264521)
							(end 0.2032 -0.2794)
						)
					)
					(width 0)
					(fill yes)
				)
			)
		)
		(pad "2" smd custom
			(at 0 0.4318 270)
			(size 0.127 0.127)
			(layers "F.Cu" "F.Mask" "F.Paste")
			(net "SMBUS_SW_EN")
			(options
				(clearance outline)
				(anchor circle)
			)
			(primitives
				(gr_poly
					(pts
						(arc
							(start -0.2032 -0.2794)
							(mid -0.239121 -0.264521)
							(end -0.254 -0.2286)
						)
						(arc
							(start -0.254 0.2286)
							(mid -0.239121 0.264521)
							(end -0.2032 0.2794)
						)
						(arc
							(start 0.2032 0.2794)
							(mid 0.239121 0.264521)
							(end 0.254 0.2286)
						)
						(arc
							(start 0.254 -0.2286)
							(mid 0.239121 -0.264521)
							(end 0.2032 -0.2794)
						)
					)
					(width 0)
					(fill yes)
				)
			)
		)
	)
	(footprint ""
		(layer "F.Cu")
		(at 163.9062 -12.828778 180)
		(property "Reference" "C342"
			(at 0 0 180)
			(layer "F.SilkS")
			(hide yes)
			(effects
				(font
					(size 1.27 1.27)
				)
			)
		)
		(property "Value" "SCD1U16V2KX-3GP"
			(at 1.8923 -1.2065 180)
			(unlocked yes)
			(layer "F.Fab")
			(hide yes)
			(effects
				(font
					(size 1.016 1.016)
					(thickness 0.1524)
				)
			)
		)
		(property "Device Type" "C402H22"
			(at 1.8923 -2.7305 180)
			(unlocked yes)
			(layer "F.Fab")
			(hide yes)
			(effects
				(font
					(size 1.016 1.016)
					(thickness 0.1524)
				)
			)
		)
		(duplicate_pad_numbers_are_jumpers no)
		(fp_rect
			(start -0.381 0.7366)
			(end 0.381 -0.7366)
			(stroke
				(width 0)
				(type default)
			)
			(fill no)
			(layer "F.CrtYd")
		)
		(fp_rect
			(start -0.381 0.7366)
			(end 0.381 -0.7366)
			(stroke
				(width 0)
				(type default)
			)
			(fill no)
			(layer "F.Fab")
		)
		(pad "1" smd custom
			(at 0 -0.4572 180)
			(size 0.1143 0.1143)
			(layers "F.Cu" "F.Mask" "F.Paste")
			(net "PV_VDDR")
			(options
				(clearance outline)
				(anchor circle)
			)
			(primitives
				(gr_poly
					(pts
						(arc
							(start -0.254 -0.1778)
							(mid -0.239121 -0.213721)
							(end -0.2032 -0.2286)
						)
						(arc
							(start 0.2032 -0.2286)
							(mid 0.239121 -0.213721)
							(end 0.254 -0.1778)
						)
						(arc
							(start 0.254 0.1778)
							(mid 0.239121 0.213721)
							(end 0.2032 0.2286)
						)
						(arc
							(start -0.2032 0.2286)
							(mid -0.239121 0.213721)
							(end -0.254 0.1778)
						)
					)
					(width 0)
					(fill yes)
				)
			)
		)
		(pad "2" smd custom
			(at 0 0.4572 180)
			(size 0.1143 0.1143)
			(layers "F.Cu" "F.Mask" "F.Paste")
			(net "GND")
			(options
				(clearance outline)
				(anchor circle)
			)
			(primitives
				(gr_poly
					(pts
						(arc
							(start -0.254 -0.1778)
							(mid -0.239121 -0.213721)
							(end -0.2032 -0.2286)
						)
						(arc
							(start 0.2032 -0.2286)
							(mid 0.239121 -0.213721)
							(end 0.254 -0.1778)
						)
						(arc
							(start 0.254 0.1778)
							(mid 0.239121 0.213721)
							(end 0.2032 0.2286)
						)
						(arc
							(start -0.2032 0.2286)
							(mid -0.239121 0.213721)
							(end -0.254 0.1778)
						)
					)
					(width 0)
					(fill yes)
				)
			)
		)
	)
	(footprint ""
		(layer "F.Cu")
		(at 18.9738 -35.3568 90)
		(property "Reference" "PR192"
			(at 0 0 90)
			(layer "F.SilkS")
			(hide yes)
			(effects
				(font
					(size 1.27 1.27)
				)
			)
		)
		(property "Value" "3K9R2F-GP"
			(at 1.7907 -1.1176 90)
			(unlocked yes)
			(layer "F.Fab")
			(hide yes)
			(effects
				(font
					(size 1.016 1.016)
					(thickness 0.1524)
				)
			)
		)
		(property "Device Type" "R402H16"
			(at 1.7907 -2.6416 90)
			(unlocked yes)
			(layer "F.Fab")
			(hide yes)
			(effects
				(font
					(size 1.016 1.016)
					(thickness 0.1524)
				)
			)
		)
		(duplicate_pad_numbers_are_jumpers no)
		(fp_rect
			(start -0.381 0.8382)
			(end 0.381 -0.8382)
			(stroke
				(width 0)
				(type default)
			)
			(fill no)
			(layer "F.CrtYd")
		)
		(fp_rect
			(start -0.381 0.8382)
			(end 0.381 -0.8382)
			(stroke
				(width 0)
				(type default)
			)
			(fill no)
			(layer "F.Fab")
		)
		(pad "1" smd custom
			(at 0 -0.4318 90)
			(size 0.127 0.127)
			(layers "F.Cu" "F.Mask" "F.Paste")
			(net "P3V3_STBY_LL")
			(options
				(clearance outline)
				(anchor circle)
			)
			(primitives
				(gr_poly
					(pts
						(arc
							(start -0.2032 -0.2794)
							(mid -0.239121 -0.264521)
							(end -0.254 -0.2286)
						)
						(arc
							(start -0.254 0.2286)
							(mid -0.239121 0.264521)
							(end -0.2032 0.2794)
						)
						(arc
							(start 0.2032 0.2794)
							(mid 0.239121 0.264521)
							(end 0.254 0.2286)
						)
						(arc
							(start 0.254 -0.2286)
							(mid 0.239121 -0.264521)
							(end 0.2032 -0.2794)
						)
					)
					(width 0)
					(fill yes)
				)
			)
		)
		(pad "2" smd custom
			(at 0 0.4318 90)
			(size 0.127 0.127)
			(layers "F.Cu" "F.Mask" "F.Paste")
			(net "P3V3_STBY_LL_R")
			(options
				(clearance outline)
				(anchor circle)
			)
			(primitives
				(gr_poly
					(pts
						(arc
							(start -0.2032 -0.2794)
							(mid -0.239121 -0.264521)
							(end -0.254 -0.2286)
						)
						(arc
							(start -0.254 0.2286)
							(mid -0.239121 0.264521)
							(end -0.2032 0.2794)
						)
						(arc
							(start 0.2032 0.2794)
							(mid 0.239121 0.264521)
							(end 0.254 0.2286)
						)
						(arc
							(start 0.254 -0.2286)
							(mid 0.239121 -0.264521)
							(end 0.2032 -0.2794)
						)
					)
					(width 0)
					(fill yes)
				)
			)
		)
	)
	(footprint ""
		(layer "F.Cu")
		(at 112.9284 -64.2874)
		(property "Reference" "R18"
			(at 0 0 0)
			(layer "F.SilkS")
			(hide yes)
			(effects
				(font
					(size 1.27 1.27)
				)
			)
		)
		(property "Value" "150KR2F-L-GP"
			(at 1.7907 -1.1176 0)
			(unlocked yes)
			(layer "F.Fab")
			(hide yes)
			(effects
				(font
					(size 1.016 1.016)
					(thickness 0.1524)
				)
			)
		)
		(property "Device Type" "R402H16"
			(at 1.7907 -2.6416 0)
			(unlocked yes)
			(layer "F.Fab")
			(hide yes)
			(effects
				(font
					(size 1.016 1.016)
					(thickness 0.1524)
				)
			)
		)
		(duplicate_pad_numbers_are_jumpers no)
		(fp_rect
			(start -0.381 0.8382)
			(end 0.381 -0.8382)
			(stroke
				(width 0)
				(type default)
			)
			(fill no)
			(layer "F.CrtYd")
		)
		(fp_rect
			(start -0.381 0.8382)
			(end 0.381 -0.8382)
			(stroke
				(width 0)
				(type default)
			)
			(fill no)
			(layer "F.Fab")
		)
		(pad "1" smd custom
			(at 0 -0.4318)
			(size 0.127 0.127)
			(layers "F.Cu" "F.Mask" "F.Paste")
			(net "CLK_GEN_INA_PG")
			(options
				(clearance outline)
				(anchor circle)
			)
			(primitives
				(gr_poly
					(pts
						(arc
							(start -0.2032 -0.2794)
							(mid -0.239121 -0.264521)
							(end -0.254 -0.2286)
						)
						(arc
							(start -0.254 0.2286)
							(mid -0.239121 0.264521)
							(end -0.2032 0.2794)
						)
						(arc
							(start 0.2032 0.2794)
							(mid 0.239121 0.264521)
							(end 0.254 0.2286)
						)
						(arc
							(start 0.254 -0.2286)
							(mid 0.239121 -0.264521)
							(end 0.2032 -0.2794)
						)
					)
					(width 0)
					(fill yes)
				)
			)
		)
		(pad "2" smd custom
			(at 0 0.4318)
			(size 0.127 0.127)
			(layers "F.Cu" "F.Mask" "F.Paste")
			(net "GND")
			(options
				(clearance outline)
				(anchor circle)
			)
			(primitives
				(gr_poly
					(pts
						(arc
							(start -0.2032 -0.2794)
							(mid -0.239121 -0.264521)
							(end -0.254 -0.2286)
						)
						(arc
							(start -0.254 0.2286)
							(mid -0.239121 0.264521)
							(end -0.2032 0.2794)
						)
						(arc
							(start 0.2032 0.2794)
							(mid 0.239121 0.264521)
							(end 0.254 0.2286)
						)
						(arc
							(start 0.254 -0.2286)
							(mid 0.239121 -0.264521)
							(end 0.2032 -0.2794)
						)
					)
					(width 0)
					(fill yes)
				)
			)
		)
	)
	(footprint ""
		(layer "F.Cu")
		(at 71.374 -30.734 -90)
		(property "Reference" "R342"
			(at 0 0 270)
			(layer "F.SilkS")
			(hide yes)
			(effects
				(font
					(size 1.27 1.27)
				)
			)
		)
		(property "Value" "1KR2F-3-GP"
			(at 0.064008 -3.993896 270)
			(unlocked yes)
			(layer "F.Fab")
			(hide yes)
			(effects
				(font
					(size 1.016 1.016)
					(thickness 0.1524)
				)
			)
		)
		(property "Device Type" "R402H16"
			(at 0.064008 -5.517896 270)
			(unlocked yes)
			(layer "F.Fab")
			(hide yes)
			(effects
				(font
					(size 1.016 1.016)
					(thickness 0.1524)
				)
			)
		)
		(duplicate_pad_numbers_are_jumpers no)
		(fp_rect
			(start -0.381 0.8382)
			(end 0.381 -0.8382)
			(stroke
				(width 0)
				(type default)
			)
			(fill no)
			(layer "F.CrtYd")
		)
		(fp_rect
			(start -0.381 0.8382)
			(end 0.381 -0.8382)
			(stroke
				(width 0)
				(type default)
			)
			(fill no)
			(layer "F.Fab")
		)
		(pad "1" smd custom
			(at 0 -0.4318 270)
			(size 0.127 0.127)
			(layers "F.Cu" "F.Mask" "F.Paste")
			(net "DDR3_DRAM_PWROK")
			(options
				(clearance outline)
				(anchor circle)
			)
			(primitives
				(gr_poly
					(pts
						(arc
							(start -0.2032 -0.2794)
							(mid -0.239121 -0.264521)
							(end -0.254 -0.2286)
						)
						(arc
							(start -0.254 0.2286)
							(mid -0.239121 0.264521)
							(end -0.2032 0.2794)
						)
						(arc
							(start 0.2032 0.2794)
							(mid 0.239121 0.264521)
							(end 0.254 0.2286)
						)
						(arc
							(start 0.254 -0.2286)
							(mid 0.239121 -0.264521)
							(end 0.2032 -0.2794)
						)
					)
					(width 0)
					(fill yes)
				)
			)
		)
		(pad "2" smd custom
			(at 0 0.4318 270)
			(size 0.127 0.127)
			(layers "F.Cu" "F.Mask" "F.Paste")
			(net "PWRGD_PVDDR_PG")
			(options
				(clearance outline)
				(anchor circle)
			)
			(primitives
				(gr_poly
					(pts
						(arc
							(start -0.2032 -0.2794)
							(mid -0.239121 -0.264521)
							(end -0.254 -0.2286)
						)
						(arc
							(start -0.254 0.2286)
							(mid -0.239121 0.264521)
							(end -0.2032 0.2794)
						)
						(arc
							(start 0.2032 0.2794)
							(mid 0.239121 0.264521)
							(end 0.254 0.2286)
						)
						(arc
							(start 0.254 -0.2286)
							(mid 0.239121 -0.264521)
							(end 0.2032 -0.2794)
						)
					)
					(width 0)
					(fill yes)
				)
			)
		)
	)
	(footprint ""
		(layer "F.Cu")
		(at 7.6708 -32.004 180)
		(property "Reference" "PR201"
			(at 0 0 180)
			(layer "F.SilkS")
			(hide yes)
			(effects
				(font
					(size 1.27 1.27)
				)
			)
		)
		(property "Value" "619KR2F-GP"
			(at 1.7907 -1.1176 180)
			(unlocked yes)
			(layer "F.Fab")
			(hide yes)
			(effects
				(font
					(size 1.016 1.016)
					(thickness 0.1524)
				)
			)
		)
		(property "Device Type" "R402H16"
			(at 1.7907 -2.6416 180)
			(unlocked yes)
			(layer "F.Fab")
			(hide yes)
			(effects
				(font
					(size 1.016 1.016)
					(thickness 0.1524)
				)
			)
		)
		(duplicate_pad_numbers_are_jumpers no)
		(fp_rect
			(start -0.381 0.8382)
			(end 0.381 -0.8382)
			(stroke
				(width 0)
				(type default)
			)
			(fill no)
			(layer "F.CrtYd")
		)
		(fp_rect
			(start -0.381 0.8382)
			(end 0.381 -0.8382)
			(stroke
				(width 0)
				(type default)
			)
			(fill no)
			(layer "F.Fab")
		)
		(pad "1" smd custom
			(at 0 -0.4318 180)
			(size 0.127 0.127)
			(layers "F.Cu" "F.Mask" "F.Paste")
			(net "AGND_P3V3_STBY")
			(options
				(clearance outline)
				(anchor circle)
			)
			(primitives
				(gr_poly
					(pts
						(arc
							(start -0.2032 -0.2794)
							(mid -0.239121 -0.264521)
							(end -0.254 -0.2286)
						)
						(arc
							(start -0.254 0.2286)
							(mid -0.239121 0.264521)
							(end -0.2032 0.2794)
						)
						(arc
							(start 0.2032 0.2794)
							(mid 0.239121 0.264521)
							(end 0.254 0.2286)
						)
						(arc
							(start 0.254 -0.2286)
							(mid 0.239121 -0.264521)
							(end 0.2032 -0.2794)
						)
					)
					(width 0)
					(fill yes)
				)
			)
		)
		(pad "2" smd custom
			(at 0 0.4318 180)
			(size 0.127 0.127)
			(layers "F.Cu" "F.Mask" "F.Paste")
			(net "P3V3_STBY_RF")
			(options
				(clearance outline)
				(anchor circle)
			)
			(primitives
				(gr_poly
					(pts
						(arc
							(start -0.2032 -0.2794)
							(mid -0.239121 -0.264521)
							(end -0.254 -0.2286)
						)
						(arc
							(start -0.254 0.2286)
							(mid -0.239121 0.264521)
							(end -0.2032 0.2794)
						)
						(arc
							(start 0.2032 0.2794)
							(mid 0.239121 0.264521)
							(end 0.254 0.2286)
						)
						(arc
							(start 0.254 -0.2286)
							(mid 0.239121 -0.264521)
							(end 0.2032 -0.2794)
						)
					)
					(width 0)
					(fill yes)
				)
			)
		)
	)
	(footprint ""
		(layer "F.Cu")
		(at 44.45 -40.132 90)
		(property "Reference" "U12"
			(at 0 0 90)
			(layer "F.SilkS")
			(hide yes)
			(effects
				(font
					(size 1.27 1.27)
				)
			)
		)
		(property "Value" "SN74LVC1G14DCKR-GP"
			(at 0 -8.0772 90)
			(unlocked yes)
			(layer "F.Fab")
			(hide yes)
			(effects
				(font
					(size 1.016 1.016)
					(thickness 0.1524)
				)
			)
		)
		(property "Device Type" "SC70-5H44"
			(at 0 -9.6012 90)
			(unlocked yes)
			(layer "F.Fab")
			(hide yes)
			(effects
				(font
					(size 1.016 1.016)
					(thickness 0.1524)
				)
			)
		)
		(duplicate_pad_numbers_are_jumpers no)
		(fp_line
			(start 1.0033 -0.3302)
			(end 1.0033 0.3302)
			(stroke
				(width 0.1524)
				(type default)
			)
			(layer "F.SilkS")
		)
		(fp_line
			(start -1.0033 -0.3302)
			(end 1.0033 -0.3302)
			(stroke
				(width 0.1524)
				(type default)
			)
			(layer "F.SilkS")
		)
		(fp_line
			(start 1.0033 0.3302)
			(end -1.0033 0.3302)
			(stroke
				(width 0.1524)
				(type default)
			)
			(layer "F.SilkS")
		)
		(fp_line
			(start -1.0033 0.3302)
			(end -1.0033 -0.3302)
			(stroke
				(width 0.1524)
				(type default)
			)
			(layer "F.SilkS")
		)
		(fp_poly
			(pts
				(xy -1.0033 1.4859) (xy -1.0033 0.8001) (xy -1.1811 0.8001) (xy -1.1811 -0.8001) (xy -1.0033 -0.8001)
				(xy -1.0033 -1.4859) (xy 1.0033 -1.4859) (xy 1.0033 -0.8001) (xy 1.1811 -0.8001) (xy 1.1811 0.8001)
				(xy 1.0033 0.8001) (xy 1.0033 1.4859) (xy 0.2921 1.4859) (xy 0.2921 0.8001) (xy -0.2921 0.8001)
				(xy -0.2921 1.4859)
			)
			(stroke
				(width 0)
				(type default)
			)
			(fill no)
			(layer "F.CrtYd")
		)
		(fp_poly
			(pts
				(xy -1.0033 1.4859) (xy -1.0033 0.8001) (xy -1.1811 0.8001) (xy -1.1811 -0.8001) (xy -1.0033 -0.8001)
				(xy -1.0033 -1.4859) (xy 1.0033 -1.4859) (xy 1.0033 -0.8001) (xy 1.1811 -0.8001) (xy 1.1811 0.8001)
				(xy 1.0033 0.8001) (xy 1.0033 1.4859) (xy 0.2921 1.4859) (xy 0.2921 0.8001) (xy -0.2921 0.8001)
				(xy -0.2921 1.4859)
			)
			(stroke
				(width 0)
				(type default)
			)
			(fill no)
			(layer "F.Fab")
		)
		(pad "1" smd rect
			(at 0.65024 -0.93472 90)
			(size 0.3556 0.762)
			(layers "F.Cu" "F.Mask" "F.Paste")
			(net "Net_406")
		)
		(pad "2" smd rect
			(at 0 -0.93472 90)
			(size 0.3556 0.762)
			(layers "F.Cu" "F.Mask" "F.Paste")
			(net "CLK_GEN_DELAY0_PG")
		)
		(pad "3" smd rect
			(at -0.65024 -0.93472 90)
			(size 0.3556 0.762)
			(layers "F.Cu" "F.Mask" "F.Paste")
			(net "GND")
		)
		(pad "4" smd rect
			(at -0.65024 0.93472 90)
			(size 0.3556 0.762)
			(layers "F.Cu" "F.Mask" "F.Paste")
			(net "CLK_GEN_DELAY1_PG")
		)
		(pad "5" smd rect
			(at 0.65024 0.93472 90)
			(size 0.3556 0.762)
			(layers "F.Cu" "F.Mask" "F.Paste")
			(net "P3V3")
		)
	)
	(footprint ""
		(layer "F.Cu")
		(at 161.7472 -12.828778 180)
		(property "Reference" "C343"
			(at 0 0 180)
			(layer "F.SilkS")
			(hide yes)
			(effects
				(font
					(size 1.27 1.27)
				)
			)
		)
		(property "Value" "SCD1U16V2KX-3GP"
			(at 1.8923 -1.2065 180)
			(unlocked yes)
			(layer "F.Fab")
			(hide yes)
			(effects
				(font
					(size 1.016 1.016)
					(thickness 0.1524)
				)
			)
		)
		(property "Device Type" "C402H22"
			(at 1.8923 -2.7305 180)
			(unlocked yes)
			(layer "F.Fab")
			(hide yes)
			(effects
				(font
					(size 1.016 1.016)
					(thickness 0.1524)
				)
			)
		)
		(duplicate_pad_numbers_are_jumpers no)
		(fp_rect
			(start -0.381 0.7366)
			(end 0.381 -0.7366)
			(stroke
				(width 0)
				(type default)
			)
			(fill no)
			(layer "F.CrtYd")
		)
		(fp_rect
			(start -0.381 0.7366)
			(end 0.381 -0.7366)
			(stroke
				(width 0)
				(type default)
			)
			(fill no)
			(layer "F.Fab")
		)
		(pad "1" smd custom
			(at 0 -0.4572 180)
			(size 0.1143 0.1143)
			(layers "F.Cu" "F.Mask" "F.Paste")
			(net "PV_VDDR")
			(options
				(clearance outline)
				(anchor circle)
			)
			(primitives
				(gr_poly
					(pts
						(arc
							(start -0.254 -0.1778)
							(mid -0.239121 -0.213721)
							(end -0.2032 -0.2286)
						)
						(arc
							(start 0.2032 -0.2286)
							(mid 0.239121 -0.213721)
							(end 0.254 -0.1778)
						)
						(arc
							(start 0.254 0.1778)
							(mid 0.239121 0.213721)
							(end 0.2032 0.2286)
						)
						(arc
							(start -0.2032 0.2286)
							(mid -0.239121 0.213721)
							(end -0.254 0.1778)
						)
					)
					(width 0)
					(fill yes)
				)
			)
		)
		(pad "2" smd custom
			(at 0 0.4572 180)
			(size 0.1143 0.1143)
			(layers "F.Cu" "F.Mask" "F.Paste")
			(net "GND")
			(options
				(clearance outline)
				(anchor circle)
			)
			(primitives
				(gr_poly
					(pts
						(arc
							(start -0.254 -0.1778)
							(mid -0.239121 -0.213721)
							(end -0.2032 -0.2286)
						)
						(arc
							(start 0.2032 -0.2286)
							(mid 0.239121 -0.213721)
							(end 0.254 -0.1778)
						)
						(arc
							(start 0.254 0.1778)
							(mid 0.239121 0.213721)
							(end 0.2032 0.2286)
						)
						(arc
							(start -0.2032 0.2286)
							(mid -0.239121 0.213721)
							(end -0.254 0.1778)
						)
					)
					(width 0)
					(fill yes)
				)
			)
		)
	)
)
